(kicad_pcb
	(version 20260206)
	(generator "pcbnew")
	(generator_version "10.0")
	(general
		(thickness 1.6)
		(legacy_teardrops no)
	)
	(paper "A4")
	(title_block
		(title "fcb — Lightning_FCB_BRD.brd")
		(comment 1 "Lightning (Wiwynn / Facebook NVMe JBOF) / footprints 151-155 of 495")
	)
	(layers
		(0 "F.Cu" signal "TOP")
		(4 "In1.Cu" signal "L2GND")
		(6 "In2.Cu" signal "L3VCC")
		(2 "B.Cu" signal "BOTTOM")
		(9 "F.Adhes" user "F.Adhesive")
		(11 "B.Adhes" user "B.Adhesive")
		(13 "F.Paste" user "Package Geometry/Pastemask Top")
		(15 "B.Paste" user "Package Geometry/Pastemask Bottom")
		(5 "F.SilkS" user "Ref Des/Silkscreen Top")
		(7 "B.SilkS" user "Ref Des/Silkscreen Bottom")
		(1 "F.Mask" user "Board Geometry/Soldermask Top")
		(3 "B.Mask" user "Board Geometry/Soldermask Bottom")
		(17 "Dwgs.User" user "User.Drawings")
		(19 "Cmts.User" user "User.Comments")
		(21 "Eco1.User" user "User.Eco1")
		(23 "Eco2.User" user "User.Eco2")
		(25 "Edge.Cuts" user "Board Geometry/Outline")
		(27 "Margin" user)
		(31 "F.CrtYd" user "Package Geometry/Place Bound Top")
		(29 "B.CrtYd" user "Package Geometry/Place Bound Bottom")
		(35 "F.Fab" user "Ref Des/Assembly Top")
		(33 "B.Fab" user "Ref Des/Assembly Bottom")
	)
	(footprint ""
		(layer "F.Cu")
		(at 37.1602 -246.5324)
		(property "Reference" "U6"
			(at 0 0 0)
			(layer "F.SilkS")
			(hide yes)
			(effects
				(font
					(size 1.27 1.27)
				)
			)
		)
		(property "Value" "PCA9551PW-T-2GP-U"
			(at 0.127 -12.573 0)
			(unlocked yes)
			(layer "F.Fab")
			(hide yes)
			(effects
				(font
					(size 1.016 1.016)
					(thickness 0.1524)
				)
			)
		)
		(property "Device Type" "TSOIC16H44"
			(at 0.1016 -14.5796 0)
			(unlocked yes)
			(layer "F.Fab")
			(hide yes)
			(effects
				(font
					(size 1.016 1.016)
					(thickness 0.1524)
				)
			)
		)
		(duplicate_pad_numbers_are_jumpers no)
		(fp_line
			(start -3.0988 -1.778)
			(end -3.0988 1.778)
			(stroke
				(width 0.1524)
				(type default)
			)
			(layer "F.SilkS")
		)
		(fp_line
			(start -3.0988 -1.778)
			(end 2.3622 -1.778)
			(stroke
				(width 0.1524)
				(type default)
			)
			(layer "F.SilkS")
		)
		(fp_line
			(start -2.921 3.81)
			(end -2.921 1.778)
			(stroke
				(width 0.508)
				(type default)
			)
			(layer "F.SilkS")
		)
		(fp_line
			(start -2.54 0)
			(end -3.0988 -0.5588)
			(stroke
				(width 0.1524)
				(type default)
			)
			(layer "F.SilkS")
		)
		(fp_line
			(start -2.54 0)
			(end -3.0988 0.5588)
			(stroke
				(width 0.1524)
				(type default)
			)
			(layer "F.SilkS")
		)
		(fp_line
			(start 2.3622 -1.778)
			(end 2.3622 1.778)
			(stroke
				(width 0.1524)
				(type default)
			)
			(layer "F.SilkS")
		)
		(fp_line
			(start 2.3622 1.778)
			(end -2.921 1.778)
			(stroke
				(width 0.1524)
				(type default)
			)
			(layer "F.SilkS")
		)
		(fp_poly
			(pts
				(xy -2.4638 -1.778) (xy -2.4638 1.778) (xy 2.3622 1.778) (xy 2.3622 -1.778)
			)
			(stroke
				(width 0)
				(type default)
			)
			(fill yes)
			(layer "F.SilkS")
		)
		(fp_rect
			(start -3.175 4.064)
			(end 3.175 -4.064)
			(stroke
				(width 0)
				(type default)
			)
			(fill no)
			(layer "F.CrtYd")
		)
		(fp_poly
			(pts
				(xy -3.175 -4.064) (xy 3.175 -4.064) (xy 3.175 4.064) (xy -3.175 4.064)
			)
			(stroke
				(width 0)
				(type default)
			)
			(fill no)
			(layer "F.Fab")
		)
		(pad "1" smd rect
			(at -2.27584 2.8194)
			(size 0.3556 1.524)
			(layers "F.Cu" "F.Mask" "F.Paste")
			(net "LED_DRV_A0")
		)
		(pad "2" smd rect
			(at -1.6256 2.8194)
			(size 0.3556 1.524)
			(layers "F.Cu" "F.Mask" "F.Paste")
			(net "LED_DRV_A1")
		)
		(pad "3" smd rect
			(at -0.97536 2.8194)
			(size 0.3556 1.524)
			(layers "F.Cu" "F.Mask" "F.Paste")
			(net "LED_DRV_A2")
		)
		(pad "4" smd rect
			(at -0.32512 2.8194)
			(size 0.3556 1.524)
			(layers "F.Cu" "F.Mask" "F.Paste")
			(net "LED_DR_LED0")
		)
		(pad "5" smd rect
			(at 0.32512 2.8194)
			(size 0.3556 1.524)
			(layers "F.Cu" "F.Mask" "F.Paste")
			(net "LED_DR_LED1")
		)
		(pad "6" smd rect
			(at 0.97536 2.8194)
			(size 0.3556 1.524)
			(layers "F.Cu" "F.Mask" "F.Paste")
			(net "LED_DR_LED2")
		)
		(pad "7" smd rect
			(at 1.6256 2.8194)
			(size 0.3556 1.524)
			(layers "F.Cu" "F.Mask" "F.Paste")
			(net "LED_DR_LED3")
		)
		(pad "8" smd rect
			(at 2.27584 2.8194)
			(size 0.3556 1.524)
			(layers "F.Cu" "F.Mask" "F.Paste")
			(net "GND")
		)
		(pad "9" smd rect
			(at 2.27584 -2.8194)
			(size 0.3556 1.524)
			(layers "F.Cu" "F.Mask" "F.Paste")
			(net "LED_DR_LED4")
		)
		(pad "10" smd rect
			(at 1.6256 -2.8194)
			(size 0.3556 1.524)
			(layers "F.Cu" "F.Mask" "F.Paste")
			(net "LED_DR_LED5")
		)
		(pad "11" smd rect
			(at 0.97536 -2.8194)
			(size 0.3556 1.524)
			(layers "F.Cu" "F.Mask" "F.Paste")
			(net "LED_DR_LED6_RESERVE")
		)
		(pad "12" smd rect
			(at 0.32512 -2.8194)
			(size 0.3556 1.524)
			(layers "F.Cu" "F.Mask" "F.Paste")
			(net "LED_DR_LED7_RESERVE")
		)
		(pad "13" smd rect
			(at -0.32512 -2.8194)
			(size 0.3556 1.524)
			(layers "F.Cu" "F.Mask" "F.Paste")
			(net "LED_DRV_RST")
		)
		(pad "14" smd rect
			(at -0.97536 -2.8194)
			(size 0.3556 1.524)
			(layers "F.Cu" "F.Mask" "F.Paste")
			(net "I2C_C_SCL_LEDDRV")
		)
		(pad "15" smd rect
			(at -1.6256 -2.8194)
			(size 0.3556 1.524)
			(layers "F.Cu" "F.Mask" "F.Paste")
			(net "I2C_C_SDA_LEDDRV")
		)
		(pad "16" smd rect
			(at -2.27584 -2.8194)
			(size 0.3556 1.524)
			(layers "F.Cu" "F.Mask" "F.Paste")
			(net "P3V3")
		)
	)
	(footprint ""
		(layer "F.Cu")
		(at 45.500036 -480.000056)
		(property "Reference" "H3"
			(at 0 0 0)
			(layer "F.SilkS")
			(hide yes)
			(effects
				(font
					(size 1.27 1.27)
				)
			)
		)
		(property "Value" "HOLE315R158"
			(at -5.08 -0.4572 0)
			(unlocked yes)
			(layer "F.Fab")
			(hide yes)
			(effects
				(font
					(size 1.016 1.016)
					(thickness 0.1524)
				)
			)
		)
		(property "Device Type" "HOLE315R158"
			(at -5.08 -1.9812 0)
			(unlocked yes)
			(layer "F.Fab")
			(hide yes)
			(effects
				(font
					(size 1.016 1.016)
					(thickness 0.1524)
				)
			)
		)
		(duplicate_pad_numbers_are_jumpers no)
		(fp_poly
			(pts
				(arc
					(start -4.3053 0)
					(mid 4.3053 0)
					(end -4.3053 0)
				)
			)
			(stroke
				(width 0)
				(type default)
			)
			(fill no)
			(layer "B.CrtYd")
		)
		(fp_poly
			(pts
				(arc
					(start -4.3053 0)
					(mid 4.3053 0)
					(end -4.3053 0)
				)
			)
			(stroke
				(width 0)
				(type default)
			)
			(fill no)
			(layer "F.CrtYd")
		)
		(fp_poly
			(pts
				(arc
					(start -4.3053 0)
					(mid 4.3053 0)
					(end -4.3053 0)
				)
			)
			(stroke
				(width 0)
				(type default)
			)
			(fill no)
			(layer "B.Fab")
		)
		(fp_poly
			(pts
				(arc
					(start -4.3053 0)
					(mid 4.3053 0)
					(end -4.3053 0)
				)
			)
			(stroke
				(width 0)
				(type default)
			)
			(fill no)
			(layer "F.Fab")
		)
		(pad "1" thru_hole circle
			(at 0 0)
			(size 8.001 8.001)
			(drill 4.0132)
			(layers "*.Cu" "*.Mask")
			(remove_unused_layers no)
			(net "GND")
			(clearance -1.4859)
			(thermal_gap 0.3048)
			(padstack
				(mode front_inner_back)
				(layer "Inner"
					(shape circle)
					(size 4.4196 4.4196)
					(clearance 0.3048)
				)
				(layer "B.Cu"
					(shape circle)
					(size 8.001 8.001)
					(clearance -1.4859)
				)
			)
		)
	)
	(footprint ""
		(layer "F.Cu")
		(at 36.6522 -282.9814)
		(property "Reference" "C48"
			(at 0 0 0)
			(layer "F.SilkS")
			(hide yes)
			(effects
				(font
					(size 1.27 1.27)
				)
			)
		)
		(property "Value" "SC1U25V3KX-1-GP"
			(at 0 -2.8194 0)
			(unlocked yes)
			(layer "F.Fab")
			(hide yes)
			(effects
				(font
					(size 1.016 1.016)
					(thickness 0.1524)
				)
			)
		)
		(property "Device Type" "C603H36"
			(at 0 -4.3434 0)
			(unlocked yes)
			(layer "F.Fab")
			(hide yes)
			(effects
				(font
					(size 1.016 1.016)
					(thickness 0.1524)
				)
			)
		)
		(duplicate_pad_numbers_are_jumpers no)
		(fp_line
			(start 0.508 0)
			(end -0.508 0)
			(stroke
				(width 0.2032)
				(type default)
			)
			(layer "F.SilkS")
		)
		(fp_rect
			(start -0.5842 1.3335)
			(end 0.5842 -1.3335)
			(stroke
				(width 0)
				(type default)
			)
			(fill no)
			(layer "F.CrtYd")
		)
		(fp_rect
			(start -0.5842 1.3335)
			(end 0.5842 -1.3335)
			(stroke
				(width 0)
				(type default)
			)
			(fill no)
			(layer "F.Fab")
		)
		(pad "1" smd custom
			(at 0 -0.762)
			(size 0.2159 0.2159)
			(layers "F.Cu" "F.Mask" "F.Paste")
			(net "P12V")
			(options
				(clearance outline)
				(anchor circle)
			)
			(primitives
				(gr_poly
					(pts
						(arc
							(start -0.3302 -0.4318)
							(mid -0.402042 -0.402042)
							(end -0.4318 -0.3302)
						)
						(arc
							(start -0.4318 0.3302)
							(mid -0.402042 0.402042)
							(end -0.3302 0.4318)
						)
						(arc
							(start 0.3302 0.4318)
							(mid 0.402042 0.402042)
							(end 0.4318 0.3302)
						)
						(arc
							(start 0.4318 -0.3302)
							(mid 0.402042 -0.402042)
							(end 0.3302 -0.4318)
						)
					)
					(width 0)
					(fill yes)
				)
			)
		)
		(pad "2" smd custom
			(at 0 0.762)
			(size 0.2159 0.2159)
			(layers "F.Cu" "F.Mask" "F.Paste")
			(net "GND")
			(options
				(clearance outline)
				(anchor circle)
			)
			(primitives
				(gr_poly
					(pts
						(arc
							(start -0.3302 -0.4318)
							(mid -0.402042 -0.402042)
							(end -0.4318 -0.3302)
						)
						(arc
							(start -0.4318 0.3302)
							(mid -0.402042 0.402042)
							(end -0.3302 0.4318)
						)
						(arc
							(start 0.3302 0.4318)
							(mid 0.402042 0.402042)
							(end 0.4318 0.3302)
						)
						(arc
							(start 0.4318 -0.3302)
							(mid 0.402042 -0.402042)
							(end 0.3302 -0.4318)
						)
					)
					(width 0)
					(fill yes)
				)
			)
		)
	)
	(footprint ""
		(layer "F.Cu")
		(at 5.947918 -434.623972 180)
		(property "Reference" "Q8"
			(at 0 0 180)
			(layer "F.SilkS")
			(hide yes)
			(effects
				(font
					(size 1.27 1.27)
				)
			)
		)
		(property "Value" "PMBS3904-1-GP"
			(at 0 -9.0932 180)
			(unlocked yes)
			(layer "F.Fab")
			(hide yes)
			(effects
				(font
					(size 1.016 1.016)
					(thickness 0.1524)
				)
			)
		)
		(property "Device Type" "SOT-23-10H44"
			(at 0 -10.6172 180)
			(unlocked yes)
			(layer "F.Fab")
			(hide yes)
			(effects
				(font
					(size 1.016 1.016)
					(thickness 0.1524)
				)
			)
		)
		(duplicate_pad_numbers_are_jumpers no)
		(fp_line
			(start 1.651 1.778)
			(end 1.651 -1.778)
			(stroke
				(width 0.1524)
				(type default)
			)
			(layer "F.SilkS")
		)
		(fp_line
			(start 1.651 -1.778)
			(end -1.651 -1.778)
			(stroke
				(width 0.1524)
				(type default)
			)
			(layer "F.SilkS")
		)
		(fp_line
			(start -0.635 1.8796)
			(end -1.7526 1.8796)
			(stroke
				(width 0.3302)
				(type default)
			)
			(layer "F.SilkS")
		)
		(fp_line
			(start -0.71628 2.15265)
			(end -1.26492 2.15265)
			(stroke
				(width 0.0127)
				(type default)
			)
			(layer "F.SilkS")
		)
		(fp_line
			(start -0.719074 2.145538)
			(end -1.265936 2.14122)
			(stroke
				(width 0.0127)
				(type default)
			)
			(layer "F.SilkS")
		)
		(fp_line
			(start -0.9906 1.86309)
			(end -0.701294 2.15265)
			(stroke
				(width 0.0127)
				(type default)
			)
			(layer "F.SilkS")
		)
		(fp_line
			(start -0.994156 1.8669)
			(end -0.987044 1.8669)
			(stroke
				(width 0.0127)
				(type default)
			)
			(layer "F.SilkS")
		)
		(fp_line
			(start -1.003808 1.876552)
			(end -0.977646 1.876552)
			(stroke
				(width 0.0127)
				(type default)
			)
			(layer "F.SilkS")
		)
		(fp_line
			(start -1.013206 1.88595)
			(end -0.967994 1.88595)
			(stroke
				(width 0.0127)
				(type default)
			)
			(layer "F.SilkS")
		)
		(fp_line
			(start -1.022858 1.895602)
			(end -0.958596 1.895602)
			(stroke
				(width 0.0127)
				(type default)
			)
			(layer "F.SilkS")
		)
		(fp_line
			(start -1.032256 1.905)
			(end -0.948944 1.905)
			(stroke
				(width 0.0127)
				(type default)
			)
			(layer "F.SilkS")
		)
		(fp_line
			(start -1.041908 1.914652)
			(end -0.939546 1.914652)
			(stroke
				(width 0.0127)
				(type default)
			)
			(layer "F.SilkS")
		)
		(fp_line
			(start -1.051306 1.92405)
			(end -0.929894 1.92405)
			(stroke
				(width 0.0127)
				(type default)
			)
			(layer "F.SilkS")
		)
		(fp_line
			(start -1.060958 1.933702)
			(end -0.920496 1.933702)
			(stroke
				(width 0.0127)
				(type default)
			)
			(layer "F.SilkS")
		)
		(fp_line
			(start -1.070356 1.9431)
			(end -0.910844 1.9431)
			(stroke
				(width 0.0127)
				(type default)
			)
			(layer "F.SilkS")
		)
		(fp_line
			(start -1.080008 1.952752)
			(end -0.901446 1.952752)
			(stroke
				(width 0.0127)
				(type default)
			)
			(layer "F.SilkS")
		)
		(fp_line
			(start -1.089406 1.96215)
			(end -0.891794 1.96215)
			(stroke
				(width 0.0127)
				(type default)
			)
			(layer "F.SilkS")
		)
		(fp_line
			(start -1.099058 1.971802)
			(end -0.882396 1.971802)
			(stroke
				(width 0.0127)
				(type default)
			)
			(layer "F.SilkS")
		)
		(fp_line
			(start -1.108456 1.9812)
			(end -0.872744 1.9812)
			(stroke
				(width 0.0127)
				(type default)
			)
			(layer "F.SilkS")
		)
		(fp_line
			(start -1.118108 1.990852)
			(end -0.863346 1.990852)
			(stroke
				(width 0.0127)
				(type default)
			)
			(layer "F.SilkS")
		)
		(fp_line
			(start -1.127506 2.00025)
			(end -0.853694 2.00025)
			(stroke
				(width 0.0127)
				(type default)
			)
			(layer "F.SilkS")
		)
		(fp_line
			(start -1.137158 2.009902)
			(end -0.844296 2.009902)
			(stroke
				(width 0.0127)
				(type default)
			)
			(layer "F.SilkS")
		)
		(fp_line
			(start -1.146556 2.0193)
			(end -0.834644 2.0193)
			(stroke
				(width 0.0127)
				(type default)
			)
			(layer "F.SilkS")
		)
		(fp_line
			(start -1.156208 2.028952)
			(end -0.825246 2.028952)
			(stroke
				(width 0.0127)
				(type default)
			)
			(layer "F.SilkS")
		)
		(fp_line
			(start -1.165606 2.03835)
			(end -0.815594 2.03835)
			(stroke
				(width 0.0127)
				(type default)
			)
			(layer "F.SilkS")
		)
		(fp_line
			(start -1.175258 2.048002)
			(end -0.806196 2.048002)
			(stroke
				(width 0.0127)
				(type default)
			)
			(layer "F.SilkS")
		)
		(fp_line
			(start -1.184656 2.0574)
			(end -0.796544 2.0574)
			(stroke
				(width 0.0127)
				(type default)
			)
			(layer "F.SilkS")
		)
		(fp_line
			(start -1.194308 2.067052)
			(end -0.787146 2.067052)
			(stroke
				(width 0.0127)
				(type default)
			)
			(layer "F.SilkS")
		)
		(fp_line
			(start -1.203706 2.07645)
			(end -0.777494 2.07645)
			(stroke
				(width 0.0127)
				(type default)
			)
			(layer "F.SilkS")
		)
		(fp_line
			(start -1.213358 2.086102)
			(end -0.768096 2.086102)
			(stroke
				(width 0.0127)
				(type default)
			)
			(layer "F.SilkS")
		)
		(fp_line
			(start -1.222756 2.0955)
			(end -0.758444 2.0955)
			(stroke
				(width 0.0127)
				(type default)
			)
			(layer "F.SilkS")
		)
		(fp_line
			(start -1.232408 2.105152)
			(end -0.749046 2.105152)
			(stroke
				(width 0.0127)
				(type default)
			)
			(layer "F.SilkS")
		)
		(fp_line
			(start -1.241806 2.11455)
			(end -0.739394 2.11455)
			(stroke
				(width 0.0127)
				(type default)
			)
			(layer "F.SilkS")
		)
		(fp_line
			(start -1.251458 2.124202)
			(end -0.729996 2.124202)
			(stroke
				(width 0.0127)
				(type default)
			)
			(layer "F.SilkS")
		)
		(fp_line
			(start -1.260856 2.1336)
			(end -0.720344 2.1336)
			(stroke
				(width 0.0127)
				(type default)
			)
			(layer "F.SilkS")
		)
		(fp_line
			(start -1.279144 2.15265)
			(end -0.701294 2.15265)
			(stroke
				(width 0.0127)
				(type default)
			)
			(layer "F.SilkS")
		)
		(fp_line
			(start -1.279398 2.152142)
			(end -0.9906 1.86309)
			(stroke
				(width 0.0127)
				(type default)
			)
			(layer "F.SilkS")
		)
		(fp_line
			(start -1.651 1.778)
			(end 1.651 1.778)
			(stroke
				(width 0.1524)
				(type default)
			)
			(layer "F.SilkS")
		)
		(fp_line
			(start -1.651 -1.778)
			(end -1.651 1.778)
			(stroke
				(width 0.1524)
				(type default)
			)
			(layer "F.SilkS")
		)
		(fp_line
			(start -1.7526 1.8796)
			(end -1.7526 0.9906)
			(stroke
				(width 0.3302)
				(type default)
			)
			(layer "F.SilkS")
		)
		(fp_poly
			(pts
				(xy -1.285748 2.159) (xy -1.285748 1.8796) (xy -1.778 1.8796) (xy -1.778 -1.8796) (xy 1.778 -1.8796)
				(xy 1.778 1.8796) (xy -0.694944 1.8796) (xy -0.694944 2.159)
			)
			(stroke
				(width 0)
				(type default)
			)
			(fill no)
			(layer "F.CrtYd")
		)
		(fp_poly
			(pts
				(xy -1.285748 2.159) (xy -1.285748 1.8796) (xy -1.778 1.8796) (xy -1.778 -1.8796) (xy 1.778 -1.8796)
				(xy 1.778 1.8796) (xy -0.694944 1.8796) (xy -0.694944 2.159)
			)
			(stroke
				(width 0)
				(type default)
			)
			(fill no)
			(layer "F.Fab")
		)
		(pad "1" smd rect
			(at -0.98425 0.9525 180)
			(size 0.762 1.143)
			(layers "F.Cu" "F.Mask" "F.Paste")
			(net "LED_DR_LED0_B")
		)
		(pad "2" smd rect
			(at 0.98425 0.9525 180)
			(size 0.762 1.143)
			(layers "F.Cu" "F.Mask" "F.Paste")
			(net "GND")
		)
		(pad "3" smd rect
			(at 0 -0.9525 180)
			(size 0.762 1.143)
			(layers "F.Cu" "F.Mask" "F.Paste")
			(net "LED_DR_LED0_BLUE")
		)
	)
	(footprint ""
		(layer "F.Cu")
		(at 16.128492 -285.014162 180)
		(property "Reference" "R93"
			(at 0 0 180)
			(layer "F.SilkS")
			(hide yes)
			(effects
				(font
					(size 1.27 1.27)
				)
			)
		)
		(property "Value" "4K7R2F-GP"
			(at 0.064008 -3.993896 180)
			(unlocked yes)
			(layer "F.Fab")
			(hide yes)
			(effects
				(font
					(size 1.016 1.016)
					(thickness 0.1524)
				)
			)
		)
		(property "Device Type" "R402H16"
			(at 0.064008 -5.517896 180)
			(unlocked yes)
			(layer "F.Fab")
			(hide yes)
			(effects
				(font
					(size 1.016 1.016)
					(thickness 0.1524)
				)
			)
		)
		(duplicate_pad_numbers_are_jumpers no)
		(fp_line
			(start 0.508 -0.9398)
			(end -0.508 -0.9398)
			(stroke
				(width 0.1524)
				(type default)
			)
			(layer "F.SilkS")
		)
		(fp_line
			(start -0.508 -0.9398)
			(end -0.508 0.9398)
			(stroke
				(width 0.1524)
				(type default)
			)
			(layer "F.SilkS")
		)
		(fp_rect
			(start -0.508 0.9398)
			(end 0.508 -0.9398)
			(stroke
				(width 0)
				(type default)
			)
			(fill no)
			(layer "F.CrtYd")
		)
		(fp_rect
			(start -0.508 0.9398)
			(end 0.508 -0.9398)
			(stroke
				(width 0)
				(type default)
			)
			(fill no)
			(layer "F.Fab")
		)
		(pad "1" smd custom
			(at 0 -0.4445 180)
			(size 0.1397 0.1397)
			(layers "F.Cu" "F.Mask" "F.Paste")
			(net "P12V")
			(options
				(clearance outline)
				(anchor circle)
			)
			(primitives
				(gr_poly
					(pts
						(arc
							(start -0.1778 -0.2794)
							(mid -0.249642 -0.249642)
							(end -0.2794 -0.1778)
						)
						(arc
							(start -0.2794 0.1778)
							(mid -0.249642 0.249642)
							(end -0.1778 0.2794)
						)
						(arc
							(start 0.1778 0.2794)
							(mid 0.249642 0.249642)
							(end 0.2794 0.1778)
						)
						(arc
							(start 0.2794 -0.1778)
							(mid 0.249642 -0.249642)
							(end 0.1778 -0.2794)
						)
					)
					(width 0)
					(fill yes)
				)
			)
		)
		(pad "2" smd custom
			(at 0 0.4445 180)
			(size 0.1397 0.1397)
			(layers "F.Cu" "F.Mask" "F.Paste")
			(net "FAN_TACH3")
			(options
				(clearance outline)
				(anchor circle)
			)
			(primitives
				(gr_poly
					(pts
						(arc
							(start -0.1778 -0.2794)
							(mid -0.249642 -0.249642)
							(end -0.2794 -0.1778)
						)
						(arc
							(start -0.2794 0.1778)
							(mid -0.249642 0.249642)
							(end -0.1778 0.2794)
						)
						(arc
							(start 0.1778 0.2794)
							(mid 0.249642 0.249642)
							(end 0.2794 0.1778)
						)
						(arc
							(start 0.2794 -0.1778)
							(mid 0.249642 -0.249642)
							(end 0.1778 -0.2794)
						)
					)
					(width 0)
					(fill yes)
				)
			)
		)
	)
)
